(kicad_pcb
	(version 20241229)
	(generator "pcbnew")
	(generator_version "9.0")
	(general
		(thickness 1.292)
		(legacy_teardrops no)
	)
	(paper "A4")
	(title_block
		(title "LPDDR5 Testbed")
		(date "2023-12-19")
		(rev "1.0.0")
		(comment 9 "footprints 128-132 of 160")
	)
	(layers
		(0 "F.Cu" signal)
		(4 "In1.Cu" power)
		(6 "In2.Cu" power)
		(8 "In3.Cu" signal)
		(10 "In4.Cu" signal)
		(2 "B.Cu" signal)
		(9 "F.Adhes" user "F.Adhesive")
		(11 "B.Adhes" user "B.Adhesive")
		(13 "F.Paste" user)
		(15 "B.Paste" user)
		(5 "F.SilkS" user "F.Silkscreen")
		(7 "B.SilkS" user "B.Silkscreen")
		(1 "F.Mask" user)
		(3 "B.Mask" user)
		(17 "Dwgs.User" user "User.Drawings")
		(19 "Cmts.User" user "User.Comments")
		(21 "Eco1.User" user "User.Eco1")
		(23 "Eco2.User" user "User.Eco2")
		(25 "Edge.Cuts" user)
		(27 "Margin" user)
		(31 "F.CrtYd" user "F.Courtyard")
		(29 "B.CrtYd" user "B.Courtyard")
		(35 "F.Fab" user)
		(33 "B.Fab" user)
	)
	(footprint "antmicro-footprints:R_Array_4x0402_Panasonic_EXB28V"
		(layer "B.Cu")
		(at 105.375 93.8)
		(property "Reference" "R23"
			(at 1.125 1.8 0)
			(unlocked yes)
			(layer "B.SilkS")
			(effects
				(font
					(size 0.7 0.7)
					(thickness 0.15)
				)
				(justify left bottom mirror)
			)
		)
		(property "Value" "R_4x100R_0402_array"
			(at -1.5 -2 180)
			(layer "B.Fab")
			(effects
				(font
					(size 0.7 0.7)
					(thickness 0.15)
				)
				(justify left bottom mirror)
			)
		)
		(property "Author" "Antmicro"
			(at 0 0 0)
			(layer "B.Fab")
			(hide yes)
			(effects
				(font
					(size 1 1)
					(thickness 0.15)
				)
				(justify mirror)
			)
		)
		(property "License" "Apache-2.0"
			(at 0 0 0)
			(layer "B.Fab")
			(hide yes)
			(effects
				(font
					(size 1 1)
					(thickness 0.15)
				)
				(justify mirror)
			)
		)
		(property "MPN" "EXB-28V101JX"
			(at 0 0 0)
			(layer "B.Fab")
			(hide yes)
			(effects
				(font
					(size 1 1)
					(thickness 0.15)
				)
				(justify mirror)
			)
		)
		(property "Manufacturer" "Panasonic"
			(at 0 0 0)
			(layer "B.Fab")
			(hide yes)
			(effects
				(font
					(size 1 1)
					(thickness 0.15)
				)
				(justify mirror)
			)
		)
		(property "Val" "R_4x100R_0402"
			(at 0 0 0)
			(layer "B.Fab")
			(hide yes)
			(effects
				(font
					(size 1 1)
					(thickness 0.15)
				)
				(justify mirror)
			)
		)
		(sheetname "Translators")
		(sheetfile "translators.kicad_sch")
		(attr smd)
		(fp_line
			(start -1.25 0.5)
			(end -1.25 -0.498)
			(stroke
				(width 0.15)
				(type solid)
			)
			(layer "B.SilkS")
		)
		(fp_line
			(start 1.25 -0.499)
			(end 1.25 0.499)
			(stroke
				(width 0.15)
				(type solid)
			)
			(layer "B.SilkS")
		)
		(fp_rect
			(start -1.25 0.8)
			(end 1.25 -0.8)
			(stroke
				(width 0.05)
				(type solid)
			)
			(fill no)
			(layer "B.CrtYd")
		)
		(fp_line
			(start -1 -0.498)
			(end -1 0.5)
			(stroke
				(width 0.15)
				(type solid)
			)
			(layer "B.Fab")
		)
		(fp_line
			(start -1 0.5)
			(end 0.998 0.5)
			(stroke
				(width 0.15)
				(type solid)
			)
			(layer "B.Fab")
		)
		(fp_line
			(start 0.998 -0.498)
			(end -1 -0.498)
			(stroke
				(width 0.15)
				(type solid)
			)
			(layer "B.Fab")
		)
		(fp_line
			(start 0.998 0.5)
			(end 0.998 -0.498)
			(stroke
				(width 0.15)
				(type solid)
			)
			(layer "B.Fab")
		)
		(pad "1" smd roundrect
			(at -0.8875 -0.45)
			(size 0.525 0.5)
			(layers "B.Cu" "B.Mask" "B.Paste")
			(roundrect_rratio 0.25)
			(net 128 "/LPDDR5/LPDDR5_A.DQ8")
			(pinfunction "R1.1")
			(pintype "passive")
		)
		(pad "2" smd roundrect
			(at -0.25 -0.45)
			(size 0.25 0.5)
			(layers "B.Cu" "B.Mask" "B.Paste")
			(roundrect_rratio 0.25)
			(net 139 "/LPDDR5/LPDDR5_A.DQ10")
			(pinfunction "R2.1")
			(pintype "passive")
		)
		(pad "3" smd roundrect
			(at 0.25 -0.45)
			(size 0.25 0.5)
			(layers "B.Cu" "B.Mask" "B.Paste")
			(roundrect_rratio 0.25)
			(net 172 "/LPDDR5/LPDDR5_A.DQ9")
			(pinfunction "R3.1")
			(pintype "passive")
		)
		(pad "4" smd roundrect
			(at 0.8875 -0.45)
			(size 0.525 0.5)
			(layers "B.Cu" "B.Mask" "B.Paste")
			(roundrect_rratio 0.25)
			(net 183 "/LPDDR5/LPDDR5_A.DQ11")
			(pinfunction "R4.1")
			(pintype "passive")
		)
		(pad "5" smd roundrect
			(at 0.8875 0.45)
			(size 0.525 0.5)
			(layers "B.Cu" "B.Mask" "B.Paste")
			(roundrect_rratio 0.25)
			(net 14 "GND")
			(pinfunction "R4.2")
			(pintype "passive")
		)
		(pad "6" smd roundrect
			(at 0.25 0.45)
			(size 0.25 0.5)
			(layers "B.Cu" "B.Mask" "B.Paste")
			(roundrect_rratio 0.25)
			(net 14 "GND")
			(pinfunction "R3.2")
			(pintype "passive")
		)
		(pad "7" smd roundrect
			(at -0.25 0.45)
			(size 0.25 0.5)
			(layers "B.Cu" "B.Mask" "B.Paste")
			(roundrect_rratio 0.25)
			(net 14 "GND")
			(pinfunction "R2.2")
			(pintype "passive")
		)
		(pad "8" smd roundrect
			(at -0.8875 0.45)
			(size 0.525 0.5)
			(layers "B.Cu" "B.Mask" "B.Paste")
			(roundrect_rratio 0.25)
			(net 14 "GND")
			(pinfunction "R1.2")
			(pintype "passive")
		)
	)
	(footprint "antmicro-footprints:R_Array_4x0402_Panasonic_EXB28V"
		(layer "B.Cu")
		(at 141.6 93.8 180)
		(property "Reference" "R61"
			(at -1.301 1.45 0)
			(unlocked yes)
			(layer "B.SilkS")
			(effects
				(font
					(size 0.7 0.7)
					(thickness 0.15)
				)
				(justify left bottom mirror)
			)
		)
		(property "Value" "R_4x100R_0402_array"
			(at -1.5 -2 0)
			(layer "B.Fab")
			(effects
				(font
					(size 0.7 0.7)
					(thickness 0.15)
				)
				(justify left bottom mirror)
			)
		)
		(property "Author" "Antmicro"
			(at 283.2 187.6 0)
			(layer "B.Fab")
			(hide yes)
			(effects
				(font
					(size 1 1)
					(thickness 0.15)
				)
				(justify mirror)
			)
		)
		(property "License" "Apache-2.0"
			(at 283.2 187.6 0)
			(layer "B.Fab")
			(hide yes)
			(effects
				(font
					(size 1 1)
					(thickness 0.15)
				)
				(justify mirror)
			)
		)
		(property "MPN" "EXB-28V101JX"
			(at 283.2 187.6 0)
			(layer "B.Fab")
			(hide yes)
			(effects
				(font
					(size 1 1)
					(thickness 0.15)
				)
				(justify mirror)
			)
		)
		(property "Manufacturer" "Panasonic"
			(at 283.2 187.6 0)
			(layer "B.Fab")
			(hide yes)
			(effects
				(font
					(size 1 1)
					(thickness 0.15)
				)
				(justify mirror)
			)
		)
		(property "Val" "R_4x100R_0402"
			(at 283.2 187.6 0)
			(layer "B.Fab")
			(hide yes)
			(effects
				(font
					(size 1 1)
					(thickness 0.15)
				)
				(justify mirror)
			)
		)
		(sheetname "Translators1")
		(sheetfile "translators.kicad_sch")
		(attr smd)
		(fp_line
			(start 1.25 -0.499)
			(end 1.25 0.499)
			(stroke
				(width 0.15)
				(type solid)
			)
			(layer "B.SilkS")
		)
		(fp_line
			(start -1.25 0.5)
			(end -1.25 -0.498)
			(stroke
				(width 0.15)
				(type solid)
			)
			(layer "B.SilkS")
		)
		(fp_rect
			(start -1.25 0.8)
			(end 1.25 -0.8)
			(stroke
				(width 0.05)
				(type solid)
			)
			(fill no)
			(layer "B.CrtYd")
		)
		(fp_line
			(start 0.998 0.5)
			(end 0.998 -0.498)
			(stroke
				(width 0.15)
				(type solid)
			)
			(layer "B.Fab")
		)
		(fp_line
			(start 0.998 -0.498)
			(end -1 -0.498)
			(stroke
				(width 0.15)
				(type solid)
			)
			(layer "B.Fab")
		)
		(fp_line
			(start -1 0.5)
			(end 0.998 0.5)
			(stroke
				(width 0.15)
				(type solid)
			)
			(layer "B.Fab")
		)
		(fp_line
			(start -1 -0.498)
			(end -1 0.5)
			(stroke
				(width 0.15)
				(type solid)
			)
			(layer "B.Fab")
		)
		(pad "1" smd roundrect
			(at -0.8875 -0.45 180)
			(size 0.525 0.5)
			(layers "B.Cu" "B.Mask" "B.Paste")
			(roundrect_rratio 0.25)
			(net 148 "/SODIMM/LPDDR5_IN_B.CA2")
			(pinfunction "R1.1")
			(pintype "passive")
		)
		(pad "2" smd roundrect
			(at -0.25 -0.45 180)
			(size 0.25 0.5)
			(layers "B.Cu" "B.Mask" "B.Paste")
			(roundrect_rratio 0.25)
			(net 149 "/SODIMM/LPDDR5_IN_B.CA3")
			(pinfunction "R2.1")
			(pintype "passive")
		)
		(pad "3" smd roundrect
			(at 0.25 -0.45 180)
			(size 0.25 0.5)
			(layers "B.Cu" "B.Mask" "B.Paste")
			(roundrect_rratio 0.25)
			(net 150 "/SODIMM/LPDDR5_IN_B.CA4")
			(pinfunction "R3.1")
			(pintype "passive")
		)
		(pad "4" smd roundrect
			(at 0.8875 -0.45 180)
			(size 0.525 0.5)
			(layers "B.Cu" "B.Mask" "B.Paste")
			(roundrect_rratio 0.25)
			(net 151 "/SODIMM/LPDDR5_IN_B.CA5")
			(pinfunction "R4.1")
			(pintype "passive")
		)
		(pad "5" smd roundrect
			(at 0.8875 0.45 180)
			(size 0.525 0.5)
			(layers "B.Cu" "B.Mask" "B.Paste")
			(roundrect_rratio 0.25)
			(net 101 "/LPDDR5/LPDDR5_B.CA5")
			(pinfunction "R4.2")
			(pintype "passive")
		)
		(pad "6" smd roundrect
			(at 0.25 0.45 180)
			(size 0.25 0.5)
			(layers "B.Cu" "B.Mask" "B.Paste")
			(roundrect_rratio 0.25)
			(net 105 "/LPDDR5/LPDDR5_B.CA4")
			(pinfunction "R3.2")
			(pintype "passive")
		)
		(pad "7" smd roundrect
			(at -0.25 0.45 180)
			(size 0.25 0.5)
			(layers "B.Cu" "B.Mask" "B.Paste")
			(roundrect_rratio 0.25)
			(net 99 "/LPDDR5/LPDDR5_B.CA3")
			(pinfunction "R2.2")
			(pintype "passive")
		)
		(pad "8" smd roundrect
			(at -0.8875 0.45 180)
			(size 0.525 0.5)
			(layers "B.Cu" "B.Mask" "B.Paste")
			(roundrect_rratio 0.25)
			(net 104 "/LPDDR5/LPDDR5_B.CA2")
			(pinfunction "R1.2")
			(pintype "passive")
		)
	)
	(footprint "antmicro-footprints:R_Array_4x0402_Panasonic_EXB28V"
		(layer "B.Cu")
		(at 115.875 93.8)
		(property "Reference" "R19"
			(at 1.025 1.8 0)
			(unlocked yes)
			(layer "B.SilkS")
			(effects
				(font
					(size 0.7 0.7)
					(thickness 0.15)
				)
				(justify left bottom mirror)
			)
		)
		(property "Value" "R_4x100R_0402_array"
			(at -1.5 -2 180)
			(layer "B.Fab")
			(effects
				(font
					(size 0.7 0.7)
					(thickness 0.15)
				)
				(justify left bottom mirror)
			)
		)
		(property "Author" "Antmicro"
			(at 0 0 0)
			(layer "B.Fab")
			(hide yes)
			(effects
				(font
					(size 1 1)
					(thickness 0.15)
				)
				(justify mirror)
			)
		)
		(property "License" "Apache-2.0"
			(at 0 0 0)
			(layer "B.Fab")
			(hide yes)
			(effects
				(font
					(size 1 1)
					(thickness 0.15)
				)
				(justify mirror)
			)
		)
		(property "MPN" "EXB-28V101JX"
			(at 0 0 0)
			(layer "B.Fab")
			(hide yes)
			(effects
				(font
					(size 1 1)
					(thickness 0.15)
				)
				(justify mirror)
			)
		)
		(property "Manufacturer" "Panasonic"
			(at 0 0 0)
			(layer "B.Fab")
			(hide yes)
			(effects
				(font
					(size 1 1)
					(thickness 0.15)
				)
				(justify mirror)
			)
		)
		(property "Val" "R_4x100R_0402"
			(at 0 0 0)
			(layer "B.Fab")
			(hide yes)
			(effects
				(font
					(size 1 1)
					(thickness 0.15)
				)
				(justify mirror)
			)
		)
		(sheetname "Translators")
		(sheetfile "translators.kicad_sch")
		(attr smd)
		(fp_line
			(start -1.25 0.5)
			(end -1.25 -0.498)
			(stroke
				(width 0.15)
				(type solid)
			)
			(layer "B.SilkS")
		)
		(fp_line
			(start 1.25 -0.499)
			(end 1.25 0.499)
			(stroke
				(width 0.15)
				(type solid)
			)
			(layer "B.SilkS")
		)
		(fp_rect
			(start -1.25 0.8)
			(end 1.25 -0.8)
			(stroke
				(width 0.05)
				(type solid)
			)
			(fill no)
			(layer "B.CrtYd")
		)
		(fp_line
			(start -1 -0.498)
			(end -1 0.5)
			(stroke
				(width 0.15)
				(type solid)
			)
			(layer "B.Fab")
		)
		(fp_line
			(start -1 0.5)
			(end 0.998 0.5)
			(stroke
				(width 0.15)
				(type solid)
			)
			(layer "B.Fab")
		)
		(fp_line
			(start 0.998 -0.498)
			(end -1 -0.498)
			(stroke
				(width 0.15)
				(type solid)
			)
			(layer "B.Fab")
		)
		(fp_line
			(start 0.998 0.5)
			(end 0.998 -0.498)
			(stroke
				(width 0.15)
				(type solid)
			)
			(layer "B.Fab")
		)
		(pad "1" smd roundrect
			(at -0.8875 -0.45)
			(size 0.525 0.5)
			(layers "B.Cu" "B.Mask" "B.Paste")
			(roundrect_rratio 0.25)
			(net 197 "/LPDDR5/LPDDR5_A.DQ5")
			(pinfunction "R1.1")
			(pintype "passive")
		)
		(pad "2" smd roundrect
			(at -0.25 -0.45)
			(size 0.25 0.5)
			(layers "B.Cu" "B.Mask" "B.Paste")
			(roundrect_rratio 0.25)
			(net 198 "/LPDDR5/LPDDR5_A.DQ4")
			(pinfunction "R2.1")
			(pintype "passive")
		)
		(pad "3" smd roundrect
			(at 0.25 -0.45)
			(size 0.25 0.5)
			(layers "B.Cu" "B.Mask" "B.Paste")
			(roundrect_rratio 0.25)
			(net 196 "/LPDDR5/LPDDR5_A.DQ6")
			(pinfunction "R3.1")
			(pintype "passive")
		)
		(pad "4" smd roundrect
			(at 0.8875 -0.45)
			(size 0.525 0.5)
			(layers "B.Cu" "B.Mask" "B.Paste")
			(roundrect_rratio 0.25)
			(net 195 "/LPDDR5/LPDDR5_A.DQ7")
			(pinfunction "R4.1")
			(pintype "passive")
		)
		(pad "5" smd roundrect
			(at 0.8875 0.45)
			(size 0.525 0.5)
			(layers "B.Cu" "B.Mask" "B.Paste")
			(roundrect_rratio 0.25)
			(net 14 "GND")
			(pinfunction "R4.2")
			(pintype "passive")
		)
		(pad "6" smd roundrect
			(at 0.25 0.45)
			(size 0.25 0.5)
			(layers "B.Cu" "B.Mask" "B.Paste")
			(roundrect_rratio 0.25)
			(net 14 "GND")
			(pinfunction "R3.2")
			(pintype "passive")
		)
		(pad "7" smd roundrect
			(at -0.25 0.45)
			(size 0.25 0.5)
			(layers "B.Cu" "B.Mask" "B.Paste")
			(roundrect_rratio 0.25)
			(net 14 "GND")
			(pinfunction "R2.2")
			(pintype "passive")
		)
		(pad "8" smd roundrect
			(at -0.8875 0.45)
			(size 0.525 0.5)
			(layers "B.Cu" "B.Mask" "B.Paste")
			(roundrect_rratio 0.25)
			(net 14 "GND")
			(pinfunction "R1.2")
			(pintype "passive")
		)
	)
	(footprint "antmicro-footprints:R_0402_1005Metric"
		(layer "B.Cu")
		(at 164.95 90.9 90)
		(descr "Resistor SMD 0402")
		(tags "resistor SMD 0402")
		(property "Reference" "R65"
			(at -0.1 0.45 0)
			(unlocked yes)
			(layer "B.SilkS")
			(effects
				(font
					(size 0.7 0.7)
					(thickness 0.15)
				)
				(justify right bottom mirror)
			)
		)
		(property "Value" "R_100R_0402"
			(at -1.011843 -1.772047 90)
			(layer "B.Fab")
			(effects
				(font
					(size 0.7 0.7)
					(thickness 0.15)
				)
				(justify right bottom mirror)
			)
		)
		(property "Author" "Antmicro"
			(at 255.85 -74.05 0)
			(layer "B.Fab")
			(hide yes)
			(effects
				(font
					(size 1 1)
					(thickness 0.15)
				)
				(justify mirror)
			)
		)
		(property "License" "Apache-2.0"
			(at 255.85 -74.05 0)
			(layer "B.Fab")
			(hide yes)
			(effects
				(font
					(size 1 1)
					(thickness 0.15)
				)
				(justify mirror)
			)
		)
		(property "MPN" "CR0402-FX-1000GLF"
			(at 255.85 -74.05 0)
			(layer "B.Fab")
			(hide yes)
			(effects
				(font
					(size 1 1)
					(thickness 0.15)
				)
				(justify mirror)
			)
		)
		(property "Manufacturer" "Bourns"
			(at 255.85 -74.05 0)
			(layer "B.Fab")
			(hide yes)
			(effects
				(font
					(size 1 1)
					(thickness 0.15)
				)
				(justify mirror)
			)
		)
		(property "Tolerance" "1%"
			(at 255.85 -74.05 0)
			(layer "B.Fab")
			(hide yes)
			(effects
				(font
					(size 1 1)
					(thickness 0.15)
				)
				(justify mirror)
			)
		)
		(property "Val" "100R"
			(at 255.85 -74.05 0)
			(layer "B.Fab")
			(hide yes)
			(effects
				(font
					(size 1 1)
					(thickness 0.15)
				)
				(justify mirror)
			)
		)
		(sheetname "Translators1")
		(sheetfile "translators.kicad_sch")
		(attr smd)
		(fp_rect
			(start -0.93 0.47)
			(end 0.93 -0.47)
			(stroke
				(width 0.05)
				(type solid)
			)
			(fill no)
			(layer "B.CrtYd")
		)
		(fp_rect
			(start -0.5 0.25)
			(end 0.5 -0.25)
			(stroke
				(width 0.15)
				(type solid)
			)
			(fill no)
			(layer "B.Fab")
		)
		(pad "1" smd roundrect
			(at -0.485 0 90)
			(size 0.59 0.64)
			(layers "B.Cu" "B.Mask" "B.Paste")
			(roundrect_rratio 0.25)
			(net 126 "/SODIMM/LPDDR5_IN_B.WCK0_P")
			(pintype "passive")
		)
		(pad "2" smd roundrect
			(at 0.485 0 90)
			(size 0.59 0.64)
			(layers "B.Cu" "B.Mask" "B.Paste")
			(roundrect_rratio 0.25)
			(net 108 "/LPDDR5/LPDDR5_B.WCK0_P")
			(pintype "passive")
		)
	)
	(footprint "antmicro-footprints:C_0402_1005Metric"
		(layer "B.Cu")
		(at 137.575 84.35 -90)
		(descr "Capacitor SMD 0402")
		(tags "capacitor SMD 0402")
		(property "Reference" "C37"
			(at 0.85 -0.325 90)
			(unlocked yes)
			(layer "B.SilkS")
			(effects
				(font
					(size 0.7 0.7)
					(thickness 0.15)
				)
				(justify left bottom mirror)
			)
		)
		(property "Value" "C_4u7_0402"
			(at -1.022927 -2.155213 90)
			(layer "B.Fab")
			(effects
				(font
					(size 0.7 0.7)
					(thickness 0.15)
				)
				(justify left bottom mirror)
			)
		)
		(property "Author" "Antmicro"
			(at 53.225 221.925 0)
			(layer "B.Fab")
			(hide yes)
			(effects
				(font
					(size 1 1)
					(thickness 0.15)
				)
				(justify mirror)
			)
		)
		(property "Dielectric" ""
			(at 53.225 221.925 0)
			(layer "B.Fab")
			(hide yes)
			(effects
				(font
					(size 1 1)
					(thickness 0.15)
				)
				(justify mirror)
			)
		)
		(property "License" "Apache-2.0"
			(at 53.225 221.925 0)
			(layer "B.Fab")
			(hide yes)
			(effects
				(font
					(size 1 1)
					(thickness 0.15)
				)
				(justify mirror)
			)
		)
		(property "MPN" "GRM155R61A475MEAAD"
			(at 53.225 221.925 0)
			(layer "B.Fab")
			(hide yes)
			(effects
				(font
					(size 1 1)
					(thickness 0.15)
				)
				(justify mirror)
			)
		)
		(property "Manufacturer" "Murata"
			(at 53.225 221.925 0)
			(layer "B.Fab")
			(hide yes)
			(effects
				(font
					(size 1 1)
					(thickness 0.15)
				)
				(justify mirror)
			)
		)
		(property "Val" "4u7"
			(at 53.225 221.925 0)
			(layer "B.Fab")
			(hide yes)
			(effects
				(font
					(size 1 1)
					(thickness 0.15)
				)
				(justify mirror)
			)
		)
		(property "Voltage" ""
			(at 53.225 221.925 0)
			(layer "B.Fab")
			(hide yes)
			(effects
				(font
					(size 1 1)
					(thickness 0.15)
				)
				(justify mirror)
			)
		)
		(sheetname "LPDDR5")
		(sheetfile "lpddr5.kicad_sch")
		(attr smd)
		(fp_rect
			(start -0.9659 0.481258)
			(end 0.9649 -0.458742)
			(stroke
				(width 0.05)
				(type solid)
			)
			(fill no)
			(layer "B.CrtYd")
		)
		(fp_line
			(start -0.499 0.25)
			(end 0.499 0.25)
			(stroke
				(width 0.15)
				(type solid)
			)
			(layer "B.Fab")
		)
		(fp_line
			(start 0.499 0.25)
			(end 0.499 -0.248)
			(stroke
				(width 0.15)
				(type solid)
			)
			(layer "B.Fab")
		)
		(fp_line
			(start -0.499 -0.248)
			(end -0.499 0.25)
			(stroke
				(width 0.15)
				(type solid)
			)
			(layer "B.Fab")
		)
		(fp_line
			(start 0.499 -0.248)
			(end -0.499 -0.248)
			(stroke
				(width 0.15)
				(type solid)
			)
			(layer "B.Fab")
		)
		(pad "1" smd roundrect
			(at -0.484 0 270)
			(size 0.59 0.64)
			(layers "B.Cu" "B.Mask" "B.Paste")
			(roundrect_rratio 0.25)
			(net 14 "GND")
			(pintype "passive")
		)
		(pad "2" smd roundrect
			(at 0.484 0 270)
			(size 0.59 0.64)
			(layers "B.Cu" "B.Mask" "B.Paste")
			(roundrect_rratio 0.25)
			(net 4 "+0V5")
			(pintype "passive")
		)
	)
)
